# S9S_MB_2U (Grand Teton) — schematic netlist excerpt (pin names and nets, part order shuffled) for the footprints in the layout excerpt that follows; sources: Cadence DE-HDL packaged netlist, KiCad conversion of 03242023_DA0F0TMBIJ0_F0T_Motherboard_J_brd_V01_OCP.brd

R670  Q_RES  0 5% CHIP  pkg 0402LF  page 230 : A = I3C_SPD_DDRABCD_CPU1_SCL ; B = I3C_SPD_DDRABCD_CPU1_R_SCL
R963  Q_RES  240 1% CHIP  pkg 0402LF  page 235 : A = PVNN_TERM_CPU1 ; B = SMB_PEHPCPU1_GTL_R_SCL

(kicad_pcb
	(version 20260206)
	(generator "pcbnew")
	(generator_version "10.0")
	(general
		(thickness 1.6)
		(legacy_teardrops no)
	)
	(paper "A4")
	(title_block
		(title "03242023_DA0F0TMBIJ0_F0T_Motherboard_J_brd_V01_OCP.brd")
		(comment 1 "Grand Teton / footprints 4341-4342 of 6105")
	)
	(layers
		(0 "F.Cu" signal "TOP")
		(4 "In1.Cu" signal "GND")
		(6 "In2.Cu" signal "IN1")
		(8 "In3.Cu" signal "GND1")
		(10 "In4.Cu" signal "IN2")
		(12 "In5.Cu" signal "GND2")
		(14 "In6.Cu" signal "IN3")
		(16 "In7.Cu" signal "GND3")
		(18 "In8.Cu" signal "VCC")
		(20 "In9.Cu" signal "VCC1")
		(22 "In10.Cu" signal "GND4")
		(24 "In11.Cu" signal "IN4")
		(26 "In12.Cu" signal "GND5")
		(28 "In13.Cu" signal "IN5")
		(30 "In14.Cu" signal "GND6")
		(32 "In15.Cu" signal "IN6")
		(34 "In16.Cu" signal "GND7")
		(2 "B.Cu" signal "BOTTOM")
		(9 "F.Adhes" user "F.Adhesive")
		(11 "B.Adhes" user "B.Adhesive")
		(13 "F.Paste" user "Package Geometry/Pastemask Top")
		(15 "B.Paste" user "Package Geometry/Pastemask Bottom")
		(5 "F.SilkS" user "Ref Des/Silkscreen Top")
		(7 "B.SilkS" user "Ref Des/Silkscreen Bottom")
		(1 "F.Mask" user "Board Geometry/Soldermask Top")
		(3 "B.Mask" user "Board Geometry/Soldermask Bottom")
		(17 "Dwgs.User" user "User.Drawings")
		(19 "Cmts.User" user "User.Comments")
		(21 "Eco1.User" user "User.Eco1")
		(23 "Eco2.User" user "User.Eco2")
		(25 "Edge.Cuts" user "Board Geometry/Outline")
		(27 "Margin" user)
		(31 "F.CrtYd" user "Package Geometry/Place Bound Top")
		(29 "B.CrtYd" user "Package Geometry/Place Bound Bottom")
		(35 "F.Fab" user "Ref Des/Assembly Top")
		(33 "B.Fab" user "Ref Des/Assembly Bottom")
	)
	(footprint ""
		(layer "B.Cu")
		(at 93.193108 -190.705232 90)
		(property "Reference" "R670"
			(at 0 0 90)
			(layer "B.SilkS")
			(hide yes)
			(effects
				(font
					(size 1.27 1.27)
				)
				(justify mirror)
			)
		)
		(property "Value" ""
			(at 0 0 90)
			(layer "B.Fab")
			(effects
				(font
					(size 1.27 1.27)
				)
				(justify mirror)
			)
		)
		(duplicate_pad_numbers_are_jumpers no)
		(fp_line
			(start 0.7874 -0.4064)
			(end -0.7874 -0.4064)
			(stroke
				(width 0.1524)
				(type default)
			)
			(layer "B.SilkS")
		)
		(fp_line
			(start -0.7874 -0.4064)
			(end -0.7874 0.4064)
			(stroke
				(width 0.1524)
				(type default)
			)
			(layer "B.SilkS")
		)
		(fp_line
			(start 0.7874 0.4064)
			(end 0.7874 -0.4064)
			(stroke
				(width 0.1524)
				(type default)
			)
			(layer "B.SilkS")
		)
		(fp_line
			(start -0.7874 0.4064)
			(end 0.7874 0.4064)
			(stroke
				(width 0.1524)
				(type default)
			)
			(layer "B.SilkS")
		)
		(fp_line
			(start 0.67945 -0.305054)
			(end 0.12065 -0.305054)
			(stroke
				(width 0.1)
				(type default)
			)
			(layer "B.Fab")
		)
		(fp_line
			(start 0.12065 -0.305054)
			(end 0.12065 -0.2794)
			(stroke
				(width 0.1)
				(type default)
			)
			(layer "B.Fab")
		)
		(fp_line
			(start -0.12065 -0.3048)
			(end -0.67945 -0.3048)
			(stroke
				(width 0.1)
				(type default)
			)
			(layer "B.Fab")
		)
		(fp_line
			(start -0.67945 -0.3048)
			(end -0.67945 0.3048)
			(stroke
				(width 0.1)
				(type default)
			)
			(layer "B.Fab")
		)
		(fp_line
			(start 0.12065 -0.2794)
			(end -0.12065 -0.2794)
			(stroke
				(width 0.1)
				(type default)
			)
			(layer "B.Fab")
		)
		(fp_line
			(start -0.12065 -0.2794)
			(end -0.12065 -0.3048)
			(stroke
				(width 0.1)
				(type default)
			)
			(layer "B.Fab")
		)
		(fp_line
			(start 0.12065 0.2794)
			(end 0.12065 0.3048)
			(stroke
				(width 0.1)
				(type default)
			)
			(layer "B.Fab")
		)
		(fp_line
			(start -0.120396 0.2794)
			(end 0.12065 0.2794)
			(stroke
				(width 0.1)
				(type default)
			)
			(layer "B.Fab")
		)
		(fp_line
			(start 0.67945 0.3048)
			(end 0.67945 -0.305054)
			(stroke
				(width 0.1)
				(type default)
			)
			(layer "B.Fab")
		)
		(fp_line
			(start 0.12065 0.3048)
			(end 0.67945 0.3048)
			(stroke
				(width 0.1)
				(type default)
			)
			(layer "B.Fab")
		)
		(fp_line
			(start -0.120396 0.3048)
			(end -0.120396 0.2794)
			(stroke
				(width 0.1)
				(type default)
			)
			(layer "B.Fab")
		)
		(fp_line
			(start -0.67945 0.3048)
			(end -0.120396 0.3048)
			(stroke
				(width 0.1)
				(type default)
			)
			(layer "B.Fab")
		)
		(pad "1" smd circle
			(at 0.40005 0 270)
			(size 0 0)
			(layers "B.Cu" "B.Mask" "B.Paste")
			(net "I3C_SPD_DDRABCD_CPU1_SCL")
		)
		(pad "2" smd circle
			(at -0.40005 0 270)
			(size 0 0)
			(layers "B.Cu" "B.Mask" "B.Paste")
			(net "I3C_SPD_DDRABCD_CPU1_R_SCL")
		)
	)
	(footprint ""
		(layer "B.Cu")
		(at 17.725136 -192.848484)
		(property "Reference" "R963"
			(at 0 0 0)
			(layer "B.SilkS")
			(hide yes)
			(effects
				(font
					(size 1.27 1.27)
				)
				(justify mirror)
			)
		)
		(property "Value" ""
			(at 0 0 0)
			(layer "B.Fab")
			(effects
				(font
					(size 1.27 1.27)
				)
				(justify mirror)
			)
		)
		(duplicate_pad_numbers_are_jumpers no)
		(fp_line
			(start -0.7874 -0.4064)
			(end -0.7874 0.4064)
			(stroke
				(width 0.1524)
				(type default)
			)
			(layer "B.SilkS")
		)
		(fp_line
			(start -0.7874 0.4064)
			(end 0.7874 0.4064)
			(stroke
				(width 0.1524)
				(type default)
			)
			(layer "B.SilkS")
		)
		(fp_line
			(start 0.7874 -0.4064)
			(end -0.7874 -0.4064)
			(stroke
				(width 0.1524)
				(type default)
			)
			(layer "B.SilkS")
		)
		(fp_line
			(start 0.7874 0.4064)
			(end 0.7874 -0.4064)
			(stroke
				(width 0.1524)
				(type default)
			)
			(layer "B.SilkS")
		)
		(fp_line
			(start -0.67945 -0.3048)
			(end -0.67945 0.3048)
			(stroke
				(width 0.1)
				(type default)
			)
			(layer "B.Fab")
		)
		(fp_line
			(start -0.67945 0.3048)
			(end -0.120396 0.3048)
			(stroke
				(width 0.1)
				(type default)
			)
			(layer "B.Fab")
		)
		(fp_line
			(start -0.12065 -0.3048)
			(end -0.67945 -0.3048)
			(stroke
				(width 0.1)
				(type default)
			)
			(layer "B.Fab")
		)
		(fp_line
			(start -0.12065 -0.2794)
			(end -0.12065 -0.3048)
			(stroke
				(width 0.1)
				(type default)
			)
			(layer "B.Fab")
		)
		(fp_line
			(start -0.120396 0.2794)
			(end 0.12065 0.2794)
			(stroke
				(width 0.1)
				(type default)
			)
			(layer "B.Fab")
		)
		(fp_line
			(start -0.120396 0.3048)
			(end -0.120396 0.2794)
			(stroke
				(width 0.1)
				(type default)
			)
			(layer "B.Fab")
		)
		(fp_line
			(start 0.12065 -0.305054)
			(end 0.12065 -0.2794)
			(stroke
				(width 0.1)
				(type default)
			)
			(layer "B.Fab")
		)
		(fp_line
			(start 0.12065 -0.2794)
			(end -0.12065 -0.2794)
			(stroke
				(width 0.1)
				(type default)
			)
			(layer "B.Fab")
		)
		(fp_line
			(start 0.12065 0.2794)
			(end 0.12065 0.3048)
			(stroke
				(width 0.1)
				(type default)
			)
			(layer "B.Fab")
		)
		(fp_line
			(start 0.12065 0.3048)
			(end 0.67945 0.3048)
			(stroke
				(width 0.1)
				(type default)
			)
			(layer "B.Fab")
		)
		(fp_line
			(start 0.67945 -0.305054)
			(end 0.12065 -0.305054)
			(stroke
				(width 0.1)
				(type default)
			)
			(layer "B.Fab")
		)
		(fp_line
			(start 0.67945 0.3048)
			(end 0.67945 -0.305054)
			(stroke
				(width 0.1)
				(type default)
			)
			(layer "B.Fab")
		)
		(pad "1" smd circle
			(at 0.40005 0 180)
			(size 0 0)
			(layers "B.Cu" "B.Mask" "B.Paste")
			(net "PVNN_TERM_CPU1")
		)
		(pad "2" smd circle
			(at -0.40005 0 180)
			(size 0 0)
			(layers "B.Cu" "B.Mask" "B.Paste")
			(net "SMB_PEHPCPU1_GTL_R_SCL")
		)
	)
)
